# BASEBOARD_FAB2 (Tioga Pass) — schematic netlist excerpt (pin names and nets, part order shuffled) for the footprints in the layout excerpt that follows; sources: Cadence DE-HDL packaged netlist, KiCad conversion of Wiwynn_Tioga_Pass_MB.brd

J4A1  SCONN288_H44441004  SCONN  pkg PIP  page 53
  \12v\(1)  = P12V_NVDIMM_DEF
  VSS(93)  = GND
  DQ(4)  = M_F_DQ<5>
  VSS(92)  = GND
  DQ(0)  = M_F_DQ<1>
  VSS(91)  = GND
  DQS9P  = M_F_DQS_DP<9>
  DQS9N  = M_F_DQS_DN<9>
  VSS(90)  = GND
  DQ(6)  = M_F_DQ<7>
  VSS(89)  = GND
  DQ(2)  = M_F_DQ<3>
  VSS(88)  = GND
  DQ(12)  = M_F_DQ<13>
  VSS(87)  = GND
  DQ(8)  = M_F_DQ<9>
  VSS(86)  = GND
  DQS10P  = M_F_DQS_DP<10>
  DQS10N  = M_F_DQS_DN<10>
  VSS(85)  = GND
  DQ(14)  = M_F_DQ<15>
  VSS(84)  = GND
  DQ(10)  = M_F_DQ<11>
  VSS(83)  = GND
  DQ(20)  = M_F_DQ<21>
  VSS(82)  = GND
  DQ(16)  = M_F_DQ<17>
  VSS(81)  = GND
  DQS11P  = M_F_DQS_DP<11>
  DQS11N  = M_F_DQS_DN<11>
  VSS(80)  = GND
  DQ(22)  = M_F_DQ<23>
  VSS(79)  = GND
  DQ(18)  = M_F_DQ<19>
  VSS(78)  = GND
  DQ(28)  = M_F_DQ<29>
  VSS(77)  = GND
  DQ(24)  = M_F_DQ<25>
  VSS(76)  = GND
  DQS12P  = M_F_DQS_DP<12>
  DQS12N  = M_F_DQS_DN<12>
  VSS(75)  = GND
  DQ(30)  = M_F_DQ<31>
  VSS(74)  = GND
  DQ(26)  = M_F_DQ<27>
  VSS(73)  = GND
  CB(4)  = M_F_ECC<5>
  VSS(72)  = GND
  CB(0)  = M_F_ECC<1>
  VSS(71)  = GND
  DQS17P  = M_F_DQS_DP<17>
  DQS17N  = M_F_DQS_DN<17>
  VSS(70)  = GND
  CB(6)  = M_F_ECC<7>
  VSS(69)  = GND
  CB(2)  = M_F_ECC<3>
  VSS(68)  = GND
  RESET_N  = M_DEF_RST_N
  VDD(25)  = PVDDQ_DEF
  CKE(0)  = M_F_CKE<0>
  VDD(24)  = PVDDQ_DEF
  ACT_N  = M_F_ACT_N
  BG(0)  = M_F_BG<0>
  VDD(23)  = PVDDQ_DEF
  A12  = M_F_MA<12>
  A9  = M_F_MA<9>
  VDD(22)  = PVDDQ_DEF
  A8  = M_F_MA<8>
  A6  = M_F_MA<6>
  VDD(21)  = PVDDQ_DEF
  A3  = M_F_MA<3>
  A1  = M_F_MA<1>
  VDD(20)  = PVDDQ_DEF
  CK0P  = M_F_CLK_DP<0>
  CK0N  = M_F_CLK_DN<0>
  VDD(19)  = PVDDQ_DEF
  VTT(1)  = PVTT_DEF
  EVENT_N  = FM_DIMM_EVENT_COD_N
  A0  = M_F_MA<0>
  VDD(18)  = PVDDQ_DEF
  BA(0)  = M_F_BA<0>
  A16_RAS_N  = M_F_MA<16>
  VDD(17)  = PVDDQ_DEF
  S0_N  = M_F_CS_N<0>
  VDD(16)  = PVDDQ_DEF
  A15_CAS_N  = M_F_MA<15>
  ODT(0)  = M_F_ODT<0>
  VDD(15)  = PVDDQ_DEF
  S1_N  = M_F_CS_N<1>
  VDD(14)  = PVDDQ_DEF
  ODT(1)  = M_F_ODT<1>
  VDD(13)  = PVDDQ_DEF
  S2_N_C(0)  = M_F_CS_N<2>
  VSS(67)  = GND
  DQ(36)  = M_F_DQ<37>
  VSS(66)  = GND
  DQ(32)  = M_F_DQ<33>
  VSS(65)  = GND
  DQS13P  = M_F_DQS_DP<13>
  DQS13N  = M_F_DQS_DN<13>
  VSS(64)  = GND
  DQ(38)  = M_F_DQ<39>
  VSS(63)  = GND
  DQ(34)  = M_F_DQ<35>
  VSS(62)  = GND
  DQ(44)  = M_F_DQ<45>
  VSS(61)  = GND
  DQ(40)  = M_F_DQ<41>
  VSS(60)  = GND
  DQS14P  = M_F_DQS_DP<14>
  DQS14N  = M_F_DQS_DN<14>
  VSS(59)  = GND
  DQ(46)  = M_F_DQ<47>
  VSS(58)  = GND
  DQ(42)  = M_F_DQ<43>
  VSS(57)  = GND
  DQ(52)  = M_F_DQ<53>
  VSS(56)  = GND
  DQ(48)  = M_F_DQ<49>
  VSS(55)  = GND
  DQS15P  = M_F_DQS_DP<15>
  DQS15N  = M_F_DQS_DN<15>
  VSS(54)  = GND
  DQ(54)  = M_F_DQ<55>
  VSS(53)  = GND
  DQ(50)  = M_F_DQ<51>
  VSS(52)  = GND
  DQ(60)  = M_F_DQ<61>
  VSS(51)  = GND
  DQ(56)  = M_F_DQ<57>
  VSS(50)  = GND
  DQS16P  = M_F_DQS_DP<16>
  DQS16N  = M_F_DQS_DN<16>
  VSS(49)  = GND
  DQ(62)  = M_F_DQ<63>
  VSS(48)  = GND
  DQ(58)  = M_F_DQ<59>
  VSS(47)  = GND
  SA(0)  = GND
  SA(1)  = GND
  SCL  = SMB_DDR_DEF_VPP_SCL
  VPP(4)  = PVPP_DEF
  VPP(3)  = PVPP_DEF
  RFU(2)  = TP_CH_F_DIMM_F0_RFU_2
  \12v\(0)  = P12V_NVDIMM_DEF
  VREFCA  = M_F_VREF
  VSS(46)  = GND
  DQ(5)  = M_F_DQ<4>
  VSS(45)  = GND
  DQ(1)  = M_F_DQ<0>
  VSS(44)  = GND
  DQS0N  = M_F_DQS_DN<0>
  DQS0P  = M_F_DQS_DP<0>
  VSS(43)  = GND
  DQ(7)  = M_F_DQ<6>
  VSS(42)  = GND
  DQ(3)  = M_F_DQ<2>
  VSS(41)  = GND
  DQ(13)  = M_F_DQ<12>
  VSS(40)  = GND
  DQ(9)  = M_F_DQ<8>
  VSS(39)  = GND
  DQS1N  = M_F_DQS_DN<1>
  DQS1P  = M_F_DQS_DP<1>
  VSS(38)  = GND
  DQ(15)  = M_F_DQ<14>
  VSS(37)  = GND
  DQ(11)  = M_F_DQ<10>
  VSS(36)  = GND
  DQ(21)  = M_F_DQ<20>
  VSS(35)  = GND
  DQ(17)  = M_F_DQ<16>
  VSS(34)  = GND
  DQS2N  = M_F_DQS_DN<2>
  DQS2P  = M_F_DQS_DP<2>
  VSS(33)  = GND
  DQ(23)  = M_F_DQ<22>
  VSS(32)  = GND
  DQ(19)  = M_F_DQ<18>
  VSS(31)  = GND
  DQ(29)  = M_F_DQ<28>
  VSS(30)  = GND
  DQ(25)  = M_F_DQ<24>
  VSS(29)  = GND
  DQS3N  = M_F_DQS_DN<3>
  DQS3P  = M_F_DQS_DP<3>
  VSS(28)  = GND
  DQ(31)  = M_F_DQ<30>
  VSS(27)  = GND
  DQ(27)  = M_F_DQ<26>
  VSS(26)  = GND
  CB(5)  = M_F_ECC<4>
  VSS(25)  = GND
  CB(1)  = M_F_ECC<0>
  VSS(24)  = GND
  DQS8N  = M_F_DQS_DN<8>
  DQS8P  = M_F_DQS_DP<8>
  VSS(23)  = GND
  CB(7)  = M_F_ECC<6>
  VSS(22)  = GND
  CB(3)  = M_F_ECC<2>
  VSS(21)  = GND
  CKE(1)  = M_F_CKE<1>
  VDD(12)  = PVDDQ_DEF
  RFU(0)  = TP_CH_F_DIMM_F0_RFU_0
  VDD(11)  = PVDDQ_DEF
  BG(1)  = M_F_BG<1>
  ALERT_N  = M_F_ALERT_N
  VDD(10)  = PVDDQ_DEF
  A11  = M_F_MA<11>
  A7  = M_F_MA<7>
  VDD(9)  = PVDDQ_DEF
  A5  = M_F_MA<5>
  A4  = M_F_MA<4>
  VDD(8)  = PVDDQ_DEF
  A2  = M_F_MA<2>
  VDD(7)  = PVDDQ_DEF
  CK1P  = M_F_CLK_DP<1>
  CK1N  = M_F_CLK_DN<1>
  VDD(6)  = PVDDQ_DEF
  VTT(0)  = PVTT_DEF
  PAR  = M_F_PAR
  VDD(5)  = PVDDQ_DEF
  BA(1)  = M_F_BA<1>
  A10  = M_F_MA<10>
  VDD(4)  = PVDDQ_DEF
  RFU(1)  = TP_CH_F_DIMM_F0_RFU_1
  A14_WE_N  = M_F_MA<14>
  VDD(3)  = PVDDQ_DEF
  SAVE_N_NC  = FM_ADR_COMPLETE_DEF_N
  VDD(2)  = PVDDQ_DEF
  A13  = M_F_MA<13>
  VDD(1)  = PVDDQ_DEF
  A17  = M_F_MA<17>
  C(2)  = M_F_C<2>
  VDD(0)  = PVDDQ_DEF
  S3_N_C(1)  = M_F_CS_N<3>
  SA(2)  = PVPP_DEF
  VSS(20)  = GND
  DQ(37)  = M_F_DQ<36>
  VSS(19)  = GND
  DQ(33)  = M_F_DQ<32>
  VSS(18)  = GND
  DQS4N  = M_F_DQS_DN<4>
  DQS4P  = M_F_DQS_DP<4>
  VSS(17)  = GND
  DQ(39)  = M_F_DQ<38>
  VSS(16)  = GND
  DQ(35)  = M_F_DQ<34>
  VSS(15)  = GND
  DQ(45)  = M_F_DQ<44>
  VSS(14)  = GND
  DQ(41)  = M_F_DQ<40>
  VSS(13)  = GND
  DQS5N  = M_F_DQS_DN<5>
  DQS5P  = M_F_DQS_DP<5>
  VSS(12)  = GND
  DQ(47)  = M_F_DQ<46>
  VSS(11)  = GND
  DQ(43)  = M_F_DQ<42>
  VSS(10)  = GND
  DQ(53)  = M_F_DQ<52>
  VSS(9)  = GND
  DQ(49)  = M_F_DQ<48>
  VSS(8)  = GND
  DQS6N  = M_F_DQS_DN<6>
  DQS6P  = M_F_DQS_DP<6>
  VSS(7)  = GND
  DQ(55)  = M_F_DQ<54>
  VSS(6)  = GND
  DQ(51)  = M_F_DQ<50>
  VSS(5)  = GND
  DQ(61)  = M_F_DQ<60>
  VSS(4)  = GND
  DQ(57)  = M_F_DQ<56>
  VSS(3)  = GND
  DQS7N  = M_F_DQS_DN<7>
  DQS7P  = M_F_DQS_DP<7>
  VSS(2)  = GND
  DQ(63)  = M_F_DQ<62>
  VSS(1)  = GND
  DQ(59)  = M_F_DQ<58>
  VSS(0)  = GND
  VDDSPD  = PVPP_DEF
  SDA  = SMB_DDR_DEF_VPP_SDA
  VPP(1)  = PVPP_DEF
  VPP(0)  = PVPP_DEF
  VPP(2)  = PVPP_DEF

(kicad_pcb
	(version 20260206)
	(generator "pcbnew")
	(generator_version "10.0")
	(general
		(thickness 1.6)
		(legacy_teardrops no)
	)
	(paper "A4")
	(title_block
		(title "Wiwynn_Tioga_Pass_MB.brd")
		(comment 1 "Tioga Pass / footprint 431 of 4770 (J4A1), pads 52-101 of 291")
	)
	(layers
		(0 "F.Cu" signal "TOP")
		(4 "In1.Cu" signal "L2GND")
		(6 "In2.Cu" signal "L3")
		(8 "In3.Cu" signal "L4GND")
		(10 "In4.Cu" signal "L5")
		(12 "In5.Cu" signal "L6GND")
		(14 "In6.Cu" signal "L7VCC")
		(16 "In7.Cu" signal "L8VCC")
		(18 "In8.Cu" signal "L9GND")
		(20 "In9.Cu" signal "L10")
		(22 "In10.Cu" signal "L11GND")
		(24 "In11.Cu" signal "L12")
		(26 "In12.Cu" signal "L13GND")
		(2 "B.Cu" signal "BOTTOM")
		(9 "F.Adhes" user "F.Adhesive")
		(11 "B.Adhes" user "B.Adhesive")
		(13 "F.Paste" user "Package Geometry/Pastemask Top")
		(15 "B.Paste" user "Package Geometry/Pastemask Bottom")
		(5 "F.SilkS" user "Ref Des/Silkscreen Top")
		(7 "B.SilkS" user "Ref Des/Silkscreen Bottom")
		(1 "F.Mask" user "Board Geometry/Soldermask Top")
		(3 "B.Mask" user "Board Geometry/Soldermask Bottom")
		(17 "Dwgs.User" user "User.Drawings")
		(19 "Cmts.User" user "User.Comments")
		(21 "Eco1.User" user "User.Eco1")
		(23 "Eco2.User" user "User.Eco2")
		(25 "Edge.Cuts" user "Board Geometry/Outline")
		(27 "Margin" user)
		(31 "F.CrtYd" user "Package Geometry/Place Bound Top")
		(29 "B.CrtYd" user "Package Geometry/Place Bound Bottom")
		(35 "F.Fab" user "Ref Des/Assembly Top")
		(33 "B.Fab" user "Ref Des/Assembly Bottom")
	)
	(footprint ""
		(layer "F.Cu")
		(at 194.700398 -152.273 90)
		(property "Reference" "J4A1"
			(at -2.699512 42.53611 0)
			(unlocked yes)
			(layer "F.SilkS")
			(effects
				(font
					(size 0.7874 0.5842)
					(thickness 0.1524)
				)
				(justify left)
			)
		)
		(property "Value" ""
			(at 0 0 90)
			(layer "F.Fab")
			(effects
				(font
					(size 1.27 1.27)
				)
			)
		)
		(duplicate_pad_numbers_are_jumpers no)
		(pad "49" smd rect
			(at 0 40.80002 90)
			(size 1.8034 0.508)
			(layers "F.Cu" "F.Mask" "F.Paste")
			(net "M_F_ECC<1>")
		)
		(pad "50" smd rect
			(at 0 41.649904 90)
			(size 1.8034 0.508)
			(layers "F.Cu" "F.Mask" "F.Paste")
			(net "GND")
		)
		(pad "51" smd rect
			(at 0 42.500042 90)
			(size 1.8034 0.508)
			(layers "F.Cu" "F.Mask" "F.Paste")
			(net "M_F_DQS_DP<17>")
		)
		(pad "52" smd rect
			(at 0 43.349926 90)
			(size 1.8034 0.508)
			(layers "F.Cu" "F.Mask" "F.Paste")
			(net "M_F_DQS_DN<17>")
		)
		(pad "53" smd rect
			(at 0 44.200064 90)
			(size 1.8034 0.508)
			(layers "F.Cu" "F.Mask" "F.Paste")
			(net "GND")
		)
		(pad "54" smd rect
			(at 0 45.049948 90)
			(size 1.8034 0.508)
			(layers "F.Cu" "F.Mask" "F.Paste")
			(net "M_F_ECC<7>")
		)
		(pad "55" smd rect
			(at 0 45.900086 90)
			(size 1.8034 0.508)
			(layers "F.Cu" "F.Mask" "F.Paste")
			(net "GND")
		)
		(pad "56" smd rect
			(at 0 46.74997 90)
			(size 1.8034 0.508)
			(layers "F.Cu" "F.Mask" "F.Paste")
			(net "M_F_ECC<3>")
		)
		(pad "57" smd rect
			(at 0 47.600108 90)
			(size 1.8034 0.508)
			(layers "F.Cu" "F.Mask" "F.Paste")
			(net "GND")
		)
		(pad "58" smd rect
			(at 0 48.449992 90)
			(size 1.8034 0.508)
			(layers "F.Cu" "F.Mask" "F.Paste")
			(net "M_DEF_RST_N")
		)
		(pad "59" smd rect
			(at 0 49.299876 90)
			(size 1.8034 0.508)
			(layers "F.Cu" "F.Mask" "F.Paste")
			(net "PVDDQ_DEF")
		)
		(pad "60" smd rect
			(at 0 50.150014 90)
			(size 1.8034 0.508)
			(layers "F.Cu" "F.Mask" "F.Paste")
			(net "M_F_CKE<0>")
		)
		(pad "61" smd rect
			(at 0 50.999898 90)
			(size 1.8034 0.508)
			(layers "F.Cu" "F.Mask" "F.Paste")
			(net "PVDDQ_DEF")
		)
		(pad "62" smd rect
			(at 0 51.850036 90)
			(size 1.8034 0.508)
			(layers "F.Cu" "F.Mask" "F.Paste")
			(net "M_F_ACT_N")
		)
		(pad "63" smd rect
			(at 0 52.69992 90)
			(size 1.8034 0.508)
			(layers "F.Cu" "F.Mask" "F.Paste")
			(net "M_F_BG<0>")
		)
		(pad "64" smd rect
			(at 0 53.550058 90)
			(size 1.8034 0.508)
			(layers "F.Cu" "F.Mask" "F.Paste")
			(net "PVDDQ_DEF")
		)
		(pad "65" smd rect
			(at 0 54.399942 90)
			(size 1.8034 0.508)
			(layers "F.Cu" "F.Mask" "F.Paste")
			(net "M_F_MA<12>")
		)
		(pad "66" smd rect
			(at 0 55.25008 90)
			(size 1.8034 0.508)
			(layers "F.Cu" "F.Mask" "F.Paste")
			(net "M_F_MA<9>")
		)
		(pad "67" smd rect
			(at 0 56.099964 90)
			(size 1.8034 0.508)
			(layers "F.Cu" "F.Mask" "F.Paste")
			(net "PVDDQ_DEF")
		)
		(pad "68" smd rect
			(at 0 56.950102 90)
			(size 1.8034 0.508)
			(layers "F.Cu" "F.Mask" "F.Paste")
			(net "M_F_MA<8>")
		)
		(pad "69" smd rect
			(at 0 57.799986 90)
			(size 1.8034 0.508)
			(layers "F.Cu" "F.Mask" "F.Paste")
			(net "M_F_MA<6>")
		)
		(pad "70" smd rect
			(at 0 58.650124 90)
			(size 1.8034 0.508)
			(layers "F.Cu" "F.Mask" "F.Paste")
			(net "PVDDQ_DEF")
		)
		(pad "71" smd rect
			(at 0 59.500008 90)
			(size 1.8034 0.508)
			(layers "F.Cu" "F.Mask" "F.Paste")
			(net "M_F_MA<3>")
		)
		(pad "72" smd rect
			(at 0 60.349892 90)
			(size 1.8034 0.508)
			(layers "F.Cu" "F.Mask" "F.Paste")
			(net "M_F_MA<1>")
		)
		(pad "73" smd rect
			(at 0 61.20003 90)
			(size 1.8034 0.508)
			(layers "F.Cu" "F.Mask" "F.Paste")
			(net "PVDDQ_DEF")
		)
		(pad "74" smd rect
			(at 0 62.049914 90)
			(size 1.8034 0.508)
			(layers "F.Cu" "F.Mask" "F.Paste")
			(net "M_F_CLK_DP<0>")
		)
		(pad "75" smd rect
			(at 0 62.900052 90)
			(size 1.8034 0.508)
			(layers "F.Cu" "F.Mask" "F.Paste")
			(net "M_F_CLK_DN<0>")
		)
		(pad "76" smd rect
			(at 0 63.749936 90)
			(size 1.8034 0.508)
			(layers "F.Cu" "F.Mask" "F.Paste")
			(net "PVDDQ_DEF")
		)
		(pad "77" smd rect
			(at 0 64.600074 90)
			(size 1.8034 0.508)
			(layers "F.Cu" "F.Mask" "F.Paste")
			(net "PVTT_DEF")
		)
		(pad "78" smd rect
			(at 0 70.550024 90)
			(size 1.8034 0.508)
			(layers "F.Cu" "F.Mask" "F.Paste")
			(net "FM_DIMM_EVENT_COD_N")
		)
		(pad "79" smd rect
			(at 0 71.399908 90)
			(size 1.8034 0.508)
			(layers "F.Cu" "F.Mask" "F.Paste")
			(net "M_F_MA<0>")
		)
		(pad "80" smd rect
			(at 0 72.250046 90)
			(size 1.8034 0.508)
			(layers "F.Cu" "F.Mask" "F.Paste")
			(net "PVDDQ_DEF")
		)
		(pad "81" smd rect
			(at 0 73.09993 90)
			(size 1.8034 0.508)
			(layers "F.Cu" "F.Mask" "F.Paste")
			(net "M_F_BA<0>")
		)
		(pad "82" smd rect
			(at 0 73.950068 90)
			(size 1.8034 0.508)
			(layers "F.Cu" "F.Mask" "F.Paste")
			(net "M_F_MA<16>")
		)
		(pad "83" smd rect
			(at 0 74.799952 90)
			(size 1.8034 0.508)
			(layers "F.Cu" "F.Mask" "F.Paste")
			(net "PVDDQ_DEF")
		)
		(pad "84" smd rect
			(at 0 75.65009 90)
			(size 1.8034 0.508)
			(layers "F.Cu" "F.Mask" "F.Paste")
			(net "M_F_CS_N<0>")
		)
		(pad "85" smd rect
			(at 0 76.499974 90)
			(size 1.8034 0.508)
			(layers "F.Cu" "F.Mask" "F.Paste")
			(net "PVDDQ_DEF")
		)
		(pad "86" smd rect
			(at 0 77.350112 90)
			(size 1.8034 0.508)
			(layers "F.Cu" "F.Mask" "F.Paste")
			(net "M_F_MA<15>")
		)
		(pad "87" smd rect
			(at 0 78.199996 90)
			(size 1.8034 0.508)
			(layers "F.Cu" "F.Mask" "F.Paste")
			(net "M_F_ODT<0>")
		)
		(pad "88" smd rect
			(at 0 79.04988 90)
			(size 1.8034 0.508)
			(layers "F.Cu" "F.Mask" "F.Paste")
			(net "PVDDQ_DEF")
		)
		(pad "89" smd rect
			(at 0 79.900018 90)
			(size 1.8034 0.508)
			(layers "F.Cu" "F.Mask" "F.Paste")
			(net "M_F_CS_N<1>")
		)
		(pad "90" smd rect
			(at 0 80.749902 90)
			(size 1.8034 0.508)
			(layers "F.Cu" "F.Mask" "F.Paste")
			(net "PVDDQ_DEF")
		)
		(pad "91" smd rect
			(at 0 81.60004 90)
			(size 1.8034 0.508)
			(layers "F.Cu" "F.Mask" "F.Paste")
			(net "M_F_ODT<1>")
		)
		(pad "92" smd rect
			(at 0 82.449924 90)
			(size 1.8034 0.508)
			(layers "F.Cu" "F.Mask" "F.Paste")
			(net "PVDDQ_DEF")
		)
		(pad "93" smd rect
			(at 0 83.300062 90)
			(size 1.8034 0.508)
			(layers "F.Cu" "F.Mask" "F.Paste")
			(net "M_F_CS_N<2>")
		)
		(pad "94" smd rect
			(at 0 84.149946 90)
			(size 1.8034 0.508)
			(layers "F.Cu" "F.Mask" "F.Paste")
			(net "GND")
		)
		(pad "95" smd rect
			(at 0 85.000084 90)
			(size 1.8034 0.508)
			(layers "F.Cu" "F.Mask" "F.Paste")
			(net "M_F_DQ<37>")
		)
		(pad "96" smd rect
			(at 0 85.849968 90)
			(size 1.8034 0.508)
			(layers "F.Cu" "F.Mask" "F.Paste")
			(net "GND")
		)
		(pad "97" smd rect
			(at 0 86.700106 90)
			(size 1.8034 0.508)
			(layers "F.Cu" "F.Mask" "F.Paste")
			(net "M_F_DQ<33>")
		)
		(pad "98" smd rect
			(at 0 87.54999 90)
			(size 1.8034 0.508)
			(layers "F.Cu" "F.Mask" "F.Paste")
			(net "GND")
		)
	)
)
